# T6G (Grand Teton) — schematic netlist excerpt (pin names and nets, part order shuffled) for the footprints in the layout excerpt that follows; sources: Cadence DE-HDL packaged netlist, KiCad conversion of 04192023_DAF0TMB3IC0_F0TG_MB_C_brd_V02_OCP.brd

C123  Q_CAP  1UF 4V 20% X6S  pkg 0201  page 323 : A = P1V8_CPU1_RT0_1A ; B = GND
C131  Q_CAP  0.1UF 10V 10% X7S  pkg C0201  page 323 : A = P1V8_CPU1_RT0_1A ; B = GND
C2378  Q_CAP  22UF 4V 20% X6S  pkg C0402  page 73 : A = PVDDCR_CPU1_P1 ; B = GND

(kicad_pcb
	(version 20260206)
	(generator "pcbnew")
	(generator_version "10.0")
	(general
		(thickness 1.6)
		(legacy_teardrops no)
	)
	(paper "A4")
	(title_block
		(title "04192023_DAF0TMB3IC0_F0TG_MB_C_brd_V02_OCP.brd")
		(comment 1 "Grand Teton / footprints 6590-6592 of 8354")
	)
	(layers
		(0 "F.Cu" signal "TOP")
		(4 "In1.Cu" signal "GND")
		(6 "In2.Cu" signal "IN1")
		(8 "In3.Cu" signal "GND1")
		(10 "In4.Cu" signal "IN2")
		(12 "In5.Cu" signal "GND2")
		(14 "In6.Cu" signal "IN3")
		(16 "In7.Cu" signal "GND3")
		(18 "In8.Cu" signal "VCC")
		(20 "In9.Cu" signal "VCC1")
		(22 "In10.Cu" signal "GND4")
		(24 "In11.Cu" signal "IN4")
		(26 "In12.Cu" signal "GND5")
		(28 "In13.Cu" signal "IN5")
		(30 "In14.Cu" signal "GND6")
		(32 "In15.Cu" signal "IN6")
		(34 "In16.Cu" signal "GND7")
		(2 "B.Cu" signal "BOTTOM")
		(9 "F.Adhes" user "F.Adhesive")
		(11 "B.Adhes" user "B.Adhesive")
		(13 "F.Paste" user "Package Geometry/Pastemask Top")
		(15 "B.Paste" user "Package Geometry/Pastemask Bottom")
		(5 "F.SilkS" user "Ref Des/Silkscreen Top")
		(7 "B.SilkS" user "Ref Des/Silkscreen Bottom")
		(1 "F.Mask" user "Board Geometry/Soldermask Top")
		(3 "B.Mask" user "Board Geometry/Soldermask Bottom")
		(17 "Dwgs.User" user "User.Drawings")
		(19 "Cmts.User" user "User.Comments")
		(21 "Eco1.User" user "User.Eco1")
		(23 "Eco2.User" user "User.Eco2")
		(25 "Edge.Cuts" user "Board Geometry/Outline")
		(27 "Margin" user)
		(31 "F.CrtYd" user "Package Geometry/Place Bound Top")
		(29 "B.CrtYd" user "Package Geometry/Place Bound Bottom")
		(35 "F.Fab" user "Ref Des/Assembly Top")
		(33 "B.Fab" user "Ref Des/Assembly Bottom")
	)
	(footprint ""
		(layer "B.Cu")
		(at 100.370386 -268.418564)
		(property "Reference" "C2378"
			(at 0 0 0)
			(layer "B.SilkS")
			(hide yes)
			(effects
				(font
					(size 1.27 1.27)
				)
				(justify mirror)
			)
		)
		(property "Value" ""
			(at 0 0 0)
			(layer "B.Fab")
			(effects
				(font
					(size 1.27 1.27)
				)
				(justify mirror)
			)
		)
		(duplicate_pad_numbers_are_jumpers no)
		(fp_line
			(start -0.7874 -0.4064)
			(end -0.7874 0.4064)
			(stroke
				(width 0.1524)
				(type default)
			)
			(layer "B.SilkS")
		)
		(fp_line
			(start -0.7874 0.4064)
			(end 0.7874 0.4064)
			(stroke
				(width 0.1524)
				(type default)
			)
			(layer "B.SilkS")
		)
		(fp_line
			(start 0.7874 -0.4064)
			(end -0.7874 -0.4064)
			(stroke
				(width 0.1524)
				(type default)
			)
			(layer "B.SilkS")
		)
		(fp_line
			(start 0.7874 0.4064)
			(end 0.7874 -0.4064)
			(stroke
				(width 0.1524)
				(type default)
			)
			(layer "B.SilkS")
		)
		(fp_line
			(start -0.67945 -0.3048)
			(end -0.67945 0.3048)
			(stroke
				(width 0.1)
				(type default)
			)
			(layer "B.Fab")
		)
		(fp_line
			(start -0.67945 0.3048)
			(end -0.120396 0.3048)
			(stroke
				(width 0.1)
				(type default)
			)
			(layer "B.Fab")
		)
		(fp_line
			(start -0.12065 -0.3048)
			(end -0.67945 -0.3048)
			(stroke
				(width 0.1)
				(type default)
			)
			(layer "B.Fab")
		)
		(fp_line
			(start -0.12065 -0.2794)
			(end -0.12065 -0.3048)
			(stroke
				(width 0.1)
				(type default)
			)
			(layer "B.Fab")
		)
		(fp_line
			(start -0.120396 0.2794)
			(end 0.12065 0.2794)
			(stroke
				(width 0.1)
				(type default)
			)
			(layer "B.Fab")
		)
		(fp_line
			(start -0.120396 0.3048)
			(end -0.120396 0.2794)
			(stroke
				(width 0.1)
				(type default)
			)
			(layer "B.Fab")
		)
		(fp_line
			(start 0.12065 -0.305054)
			(end 0.12065 -0.2794)
			(stroke
				(width 0.1)
				(type default)
			)
			(layer "B.Fab")
		)
		(fp_line
			(start 0.12065 -0.2794)
			(end -0.12065 -0.2794)
			(stroke
				(width 0.1)
				(type default)
			)
			(layer "B.Fab")
		)
		(fp_line
			(start 0.12065 0.2794)
			(end 0.12065 0.3048)
			(stroke
				(width 0.1)
				(type default)
			)
			(layer "B.Fab")
		)
		(fp_line
			(start 0.12065 0.3048)
			(end 0.67945 0.3048)
			(stroke
				(width 0.1)
				(type default)
			)
			(layer "B.Fab")
		)
		(fp_line
			(start 0.67945 -0.305054)
			(end 0.12065 -0.305054)
			(stroke
				(width 0.1)
				(type default)
			)
			(layer "B.Fab")
		)
		(fp_line
			(start 0.67945 0.3048)
			(end 0.67945 -0.305054)
			(stroke
				(width 0.1)
				(type default)
			)
			(layer "B.Fab")
		)
		(pad "1" smd circle
			(at 0.40005 0 180)
			(size 0 0)
			(layers "B.Cu" "B.Mask" "B.Paste")
			(net "PVDDCR_CPU1_P1")
		)
		(pad "2" smd circle
			(at -0.40005 0 180)
			(size 0 0)
			(layers "B.Cu" "B.Mask" "B.Paste")
			(net "GND")
		)
	)
	(footprint ""
		(layer "B.Cu")
		(at 56.97855 -386.766562 90)
		(property "Reference" "C131"
			(at 0 0 90)
			(layer "B.SilkS")
			(hide yes)
			(effects
				(font
					(size 1.27 1.27)
				)
				(justify mirror)
			)
		)
		(property "Value" ""
			(at 0 0 90)
			(layer "B.Fab")
			(effects
				(font
					(size 1.27 1.27)
				)
				(justify mirror)
			)
		)
		(duplicate_pad_numbers_are_jumpers no)
		(fp_line
			(start 0.299974 -0.150114)
			(end -0.299974 -0.150114)
			(stroke
				(width 0.1)
				(type default)
			)
			(layer "B.Fab")
		)
		(fp_line
			(start -0.299974 -0.150114)
			(end -0.299974 0.150114)
			(stroke
				(width 0.1)
				(type default)
			)
			(layer "B.Fab")
		)
		(fp_line
			(start 0.299974 0.150114)
			(end 0.299974 -0.150114)
			(stroke
				(width 0.1)
				(type default)
			)
			(layer "B.Fab")
		)
		(fp_line
			(start -0.299974 0.150114)
			(end 0.299974 0.150114)
			(stroke
				(width 0.1)
				(type default)
			)
			(layer "B.Fab")
		)
		(pad "1" smd rect
			(at 0.2667 0 270)
			(size 0.3048 0.381)
			(layers "B.Cu" "B.Mask" "B.Paste")
			(net "P1V8_CPU1_RT0_1A")
		)
		(pad "2" smd rect
			(at -0.2667 0 270)
			(size 0.3048 0.381)
			(layers "B.Cu" "B.Mask" "B.Paste")
			(net "GND")
		)
	)
	(footprint ""
		(layer "B.Cu")
		(at 54.718458 -388.011162 -90)
		(property "Reference" "C123"
			(at 0 0 90)
			(layer "B.SilkS")
			(hide yes)
			(effects
				(font
					(size 1.27 1.27)
				)
				(justify mirror)
			)
		)
		(property "Value" ""
			(at 0 0 90)
			(layer "B.Fab")
			(effects
				(font
					(size 1.27 1.27)
				)
				(justify mirror)
			)
		)
		(duplicate_pad_numbers_are_jumpers no)
		(fp_line
			(start -0.299974 0.150114)
			(end 0.299974 0.150114)
			(stroke
				(width 0.1)
				(type default)
			)
			(layer "B.Fab")
		)
		(fp_line
			(start 0.299974 0.150114)
			(end 0.299974 -0.150114)
			(stroke
				(width 0.1)
				(type default)
			)
			(layer "B.Fab")
		)
		(fp_line
			(start -0.299974 -0.150114)
			(end -0.299974 0.150114)
			(stroke
				(width 0.1)
				(type default)
			)
			(layer "B.Fab")
		)
		(fp_line
			(start 0.299974 -0.150114)
			(end -0.299974 -0.150114)
			(stroke
				(width 0.1)
				(type default)
			)
			(layer "B.Fab")
		)
		(pad "1" smd rect
			(at 0.2667 0 90)
			(size 0.3048 0.381)
			(layers "B.Cu" "B.Mask" "B.Paste")
			(net "P1V8_CPU1_RT0_1A")
		)
		(pad "2" smd rect
			(at -0.2667 0 90)
			(size 0.3048 0.381)
			(layers "B.Cu" "B.Mask" "B.Paste")
			(net "GND")
		)
	)
)
